# S9S_MB_2U (Grand Teton) — schematic netlist excerpt (pin names and nets, part order shuffled) for the footprints in the layout excerpt that follows; sources: Cadence DE-HDL packaged netlist, KiCad conversion of 03242023_DA0F0TMBIJ0_F0T_Motherboard_J_brd_V01_OCP.brd

J10  SCONN288_ADR50017P087CC  SCONN288_ADR50017-P087CC IO  pkg DDR288S_1-1VXB  page 91
  VIN_BULK0  = P12V_S3_AUX_CPU0_NVDIMM
  RFU0  = TP_CHE_CPU0_DIMM2_FRU_0
  VIN_MGMT  = P3V3_AUX
  HSCL  = I3C_SPD_DDREFGH_CPU0_LVC1_SCL_1
  HSDA  = I3C_SPD_DDREFGH_CPU0_LVC1_SDA
  VSS0  = GND
  DQ0_A  = M_E_CPU0_SA_DQ<0>
  VSS1  = GND
  DQ1_A  = M_E_CPU0_SA_DQ<1>
  VSS2  = GND
  DQS0_A_T  = M_E_CPU0_SA_DQS_DP<0>
  DQS0_A_C  = M_E_CPU0_SA_DQS_DN<0>
  VSS3  = GND
  DQ4_A  = M_E_CPU0_SA_DQ<4>
  VSS4  = GND
  DQ5_A  = M_E_CPU0_SA_DQ<5>
  VSS5  = GND
  DQ8_A  = M_E_CPU0_SA_DQ<8>
  VSS6  = GND
  DQ9_A  = M_E_CPU0_SA_DQ<9>
  VSS7  = GND
  DQS1_A_T  = M_E_CPU0_SA_DQS_DP<1>
  DQS1_A_C  = M_E_CPU0_SA_DQS_DN<1>
  VSS8  = GND
  DQ12_A  = M_E_CPU0_SA_DQ<12>
  VSS9  = GND
  DQ13_A  = M_E_CPU0_SA_DQ<13>
  VSS10  = GND
  DQ16_A  = M_E_CPU0_SA_DQ<16>
  VSS11  = GND
  DQ17_A  = M_E_CPU0_SA_DQ<17>
  VSS12  = GND
  DQS2_A_T  = M_E_CPU0_SA_DQS_DP<2>
  DQS2_A_C  = M_E_CPU0_SA_DQS_DN<2>
  VSS13  = GND
  DQ20_A  = M_E_CPU0_SA_DQ<20>
  VSS14  = GND
  DQ21_A  = M_E_CPU0_SA_DQ<21>
  VSS15  = GND
  DQ24_A  = M_E_CPU0_SA_DQ<24>
  VSS16  = GND
  DQ25_A  = M_E_CPU0_SA_DQ<25>
  VSS17  = GND
  DQS3_A_T  = M_E_CPU0_SA_DQS_DP<3>
  DQS3_A_C  = M_E_CPU0_SA_DQS_DN<3>
  VSS18  = GND
  DQ28_A  = M_E_CPU0_SA_DQ<28>
  VSS19  = GND
  DQ29_A  = M_E_CPU0_SA_DQ<29>
  VSS20  = GND
  CB0_A  = M_E_CPU0_SA_CB<0>
  VSS21  = GND
  CB1_A  = M_E_CPU0_SA_CB<1>
  VSS22  = GND
  DQS4_A_T  = M_E_CPU0_SA_DQS_DP<4>
  DQS4_A_C  = M_E_CPU0_SA_DQS_DN<4>
  VSS23  = GND
  CB4_A  = M_E_CPU0_SA_CB<4>
  VSS24  = GND
  CB5_A  = M_E_CPU0_SA_CB<5>
  VSS25  = GND
  ALERT_N  = M_E_CPU0_ALERT_N
  VSS26  = GND
  CS0_A_N  = M_E_CPU0_SA_CS_N<2>
  VSS27  = GND
  CA0_A  = M_E_CPU0_SA_CA<0>
  VSS28  = GND
  CA2_A  = M_E_CPU0_SA_CA<2>
  VSS29  = GND
  CA4_A  = M_E_CPU0_SA_CA<4>
  VSS30  = GND
  CA6_A  = M_E_CPU0_SA_CA<6>
  VSS31  = GND
  PAR_A  = M_E_CPU0_SA_PAR
  VSS32  = GND
  CA0_B  = M_E_CPU0_SB_CA<0>
  VSS33  = GND
  CA2_B  = M_E_CPU0_SB_CA<2>
  VSS34  = GND
  CA4_B  = M_E_CPU0_SB_CA<4>
  VSS35  = GND
  CA6_B  = M_E_CPU0_SB_CA<6>
  VSS36  = GND
  CS0_B_N  = M_E_CPU0_SB_CS_N<2>
  VSS37  = GND
  \lbd||rsp_a_n\  = M_E_CPU0_SA_RSP<1>
  \lbs||rsp_b_n\  = M_E_CPU0_SB_RSP<1>
  VSS38  = GND
  CB4_B  = M_E_CPU0_SB_CB<4>
  VSS39  = GND
  CB5_B  = M_E_CPU0_SB_CB<5>
  VSS40  = GND
  \dqs9_b_t||tdqs9_b_t||dbi4_b_n\  = M_E_CPU0_SB_DQS_DP<9>
  \dqs9_b_c||tdqs9_b_c\  = M_E_CPU0_SB_DQS_DN<9>
  VSS41  = GND
  CB0_B  = M_E_CPU0_SB_CB<0>
  VSS42  = GND
  CB1_B  = M_E_CPU0_SB_CB<1>
  VSS43  = GND
  DQ0_B  = M_E_CPU0_SB_DQ<0>
  VSS44  = GND
  DQ1_B  = M_E_CPU0_SB_DQ<1>
  VSS45  = GND
  DQS0_B_T  = M_E_CPU0_SB_DQS_DP<0>
  DQS0_B_C  = M_E_CPU0_SB_DQS_DN<0>
  VSS46  = GND
  DQ4_B  = M_E_CPU0_SB_DQ<4>
  VSS47  = GND
  DQ5_B  = M_E_CPU0_SB_DQ<5>
  VSS48  = GND
  DQ8_B  = M_E_CPU0_SB_DQ<8>
  VSS49  = GND
  DQ9_B  = M_E_CPU0_SB_DQ<9>
  VSS50  = GND
  DQS1_B_T  = M_E_CPU0_SB_DQS_DP<1>
  DQS1_B_C  = M_E_CPU0_SB_DQS_DN<1>
  VSS51  = GND
  DQ12_B  = M_E_CPU0_SB_DQ<12>
  VSS52  = GND
  DQ13_B  = M_E_CPU0_SB_DQ<13>
  VSS53  = GND
  DQ16_B  = M_E_CPU0_SB_DQ<16>
  VSS54  = GND
  DQ17_B  = M_E_CPU0_SB_DQ<17>
  VSS55  = GND
  DQS2_B_T  = M_E_CPU0_SB_DQS_DP<2>
  DQS2_B_C  = M_E_CPU0_SB_DQS_DN<2>
  VSS56  = GND
  DQ20_B  = M_E_CPU0_SB_DQ<20>
  VSS57  = GND
  DQ21_B  = M_E_CPU0_SB_DQ<21>
  VSS58  = GND
  DQ24_B  = M_E_CPU0_SB_DQ<24>
  VSS59  = GND
  DQ25_B  = M_E_CPU0_SB_DQ<25>
  VSS60  = GND
  DQS3_B_T  = M_E_CPU0_SB_DQS_DP<3>
  DQS3_B_C  = M_E_CPU0_SB_DQS_DN<3>
  VSS61  = GND
  DQ28_B  = M_E_CPU0_SB_DQ<28>
  VSS62  = GND
  DQ29_B  = M_E_CPU0_SB_DQ<29>
  VSS63  = GND
  RFU1  = TP_CHE_CPU0_DIMM2_FRU_1
  VIN_BULK1  = P12V_S3_AUX_CPU0_NVDIMM
  VIN_BULK2  = P12V_S3_AUX_CPU0_NVDIMM
  \pwr_good||fail_n\  = PWRGD_CHE_CPU0_DIMM2
  HSA  = PD_CHE_CPU0_DIMM2_SAA
  RFU2  = TP_CHE_CPU0_DIMM2_FRU_2
  RFU3  = TP_CHE_CPU0_DIMM2_FRU_3
  VSS64  = GND
  DQ2_A  = M_E_CPU0_SA_DQ<2>
  VSS65  = GND
  DQ3_A  = M_E_CPU0_SA_DQ<3>
  VSS66  = GND
  \dqs5_a_c||tdqs5_a_c||dqs5_a_t||tdqs5_a_t\  = M_E_CPU0_SA_DQS_DN<5>
  \dqs5_a_t||tdqs5_a_t\  = M_E_CPU0_SA_DQS_DP<5>
  VSS67  = GND
  DQ6_A  = M_E_CPU0_SA_DQ<6>
  VSS68  = GND
  DQ7_A  = M_E_CPU0_SA_DQ<7>
  VSS69  = GND
  DQ10_A  = M_E_CPU0_SA_DQ<10>
  VSS70  = GND
  DQ11_A  = M_E_CPU0_SA_DQ<11>
  VSS71  = GND
  \dqs6_a_c||tdqs6_a_c||dqs6_a_t||tdqs6_a_t\  = M_E_CPU0_SA_DQS_DN<6>
  \dqs6_a_t||tdqs6_a_t\  = M_E_CPU0_SA_DQS_DP<6>
  VSS72  = GND
  DQ14_A  = M_E_CPU0_SA_DQ<14>
  VSS73  = GND
  DQ15_A  = M_E_CPU0_SA_DQ<15>
  VSS74  = GND
  DQ18_A  = M_E_CPU0_SA_DQ<18>
  VSS75  = GND
  DQ19_A  = M_E_CPU0_SA_DQ<19>
  VSS76  = GND
  \dqs7_a_c||tdqs7_a_c\  = M_E_CPU0_SA_DQS_DN<7>
  \dqs7_a_t||tdqs7_a_t\  = M_E_CPU0_SA_DQS_DP<7>
  VSS77  = GND
  DQ22_A  = M_E_CPU0_SA_DQ<22>
  VSS78  = GND
  DQ23_A  = M_E_CPU0_SA_DQ<23>
  VSS79  = GND
  DQ26_A  = M_E_CPU0_SA_DQ<26>
  VSS80  = GND
  DQ27_A  = M_E_CPU0_SA_DQ<27>
  VSS81  = GND
  \dqs8_a_c||tdqs8_a_c\  = M_E_CPU0_SA_DQS_DN<8>
  \dqs8_a_t||tdqs8_a_t\  = M_E_CPU0_SA_DQS_DP<8>
  VSS82  = GND
  DQ30_A  = M_E_CPU0_SA_DQ<30>
  VSS83  = GND
  DQ31_A  = M_E_CPU0_SA_DQ<31>
  VSS84  = GND
  CB2_A  = M_E_CPU0_SA_CB<2>
  VSS85  = GND
  CB3_A  = M_E_CPU0_SA_CB<3>
  VSS86  = GND
  \dqs9_a_c||tdqs9_a_c\  = M_E_CPU0_SA_DQS_DN<9>
  \dqs9_a_t||tdqs9_a_t\  = M_E_CPU0_SA_DQS_DP<9>
  VSS87  = GND
  CB6_A  = M_E_CPU0_SA_CB<6>
  VSS88  = GND
  CB7_A  = M_E_CPU0_SA_CB<7>
  VSS89  = GND
  RESET_N  = RST_M_EF_CPU0_FPGA_N
  VSS90  = GND
  CS1_A_N  = M_E_CPU0_SA_CS_N<3>
  VSS91  = GND
  CA1_A  = M_E_CPU0_SA_CA<1>
  VSS92  = GND
  CA3_A  = M_E_CPU0_SA_CA<3>
  VSS93  = GND
  CA5_A  = M_E_CPU0_SA_CA<5>
  VSS94  = GND
  CK_T  = M_E_CPU0_CLK_DP<1>
  CK_C  = M_E_CPU0_CLK_DN<1>
  VSS95  = GND
  RFU4  = TP_CHE_CPU0_DIMM2_FRU_4
  CA1_B  = M_E_CPU0_SB_CA<1>
  VSS96  = GND
  CA3_B  = M_E_CPU0_SB_CA<3>
  VSS97  = GND
  CA5_B  = M_E_CPU0_SB_CA<5>
  VSS98  = GND
  PAR_B  = M_E_CPU0_SB_PAR
  VSS99  = GND
  CS1_B_N  = M_E_CPU0_SB_CS_N<3>
  VSS100  = GND
  RFU5  = TP_CHE_CPU0_DIMM2_FRU_5
  RFU6  = TP_CHE_CPU0_DIMM2_FRU_6
  VSS101  = GND
  CB6_B  = M_E_CPU0_SB_CB<6>
  VSS102  = GND
  CB7_B  = M_E_CPU0_SB_CB<7>
  VSS103  = GND
  DQS4_B_C  = M_E_CPU0_SB_DQS_DN<4>
  DQS4_B_T  = M_E_CPU0_SB_DQS_DP<4>
  VSS104  = GND
  CB2_B  = M_E_CPU0_SB_CB<2>
  VSS105  = GND
  CB3_B  = M_E_CPU0_SB_CB<3>
  VSS106  = GND
  DQ2_B  = M_E_CPU0_SB_DQ<2>
  VSS107  = GND
  DQ3_B  = M_E_CPU0_SB_DQ<3>
  VSS108  = GND
  \dqs5_b_c||tdqs5_b_c\  = M_E_CPU0_SB_DQS_DN<5>
  \dqs5_b_t||tdqs5_b_t\  = M_E_CPU0_SB_DQS_DP<5>
  VSS109  = GND
  DQ6_B  = M_E_CPU0_SB_DQ<6>
  VSS110  = GND
  DQ7_B  = M_E_CPU0_SB_DQ<7>
  VSS111  = GND
  DQ10_B  = M_E_CPU0_SB_DQ<10>
  VSS112  = GND
  DQ11_B  = M_E_CPU0_SB_DQ<11>
  VSS113  = GND
  \dqs6_b_c||tdqs6_b_c\  = M_E_CPU0_SB_DQS_DN<6>
  \dqs6_b_t||tdqs6_b_t\  = M_E_CPU0_SB_DQS_DP<6>
  VSS114  = GND
  DQ14_B  = M_E_CPU0_SB_DQ<14>
  VSS115  = GND
  DQ15_B  = M_E_CPU0_SB_DQ<15>
  VSS116  = GND
  DQ18_B  = M_E_CPU0_SB_DQ<18>
  VSS117  = GND
  DQ19_B  = M_E_CPU0_SB_DQ<19>
  VSS118  = GND
  \dqs7_b_c||tdqs7_b_c\  = M_E_CPU0_SB_DQS_DN<7>
  \dqs7_b_t||tdqs7_b_t\  = M_E_CPU0_SB_DQS_DP<7>
  VSS119  = GND
  DQ22_B  = M_E_CPU0_SB_DQ<22>
  VSS120  = GND
  DQ23_B  = M_E_CPU0_SB_DQ<23>
  VSS121  = GND
  DQ26_B  = M_E_CPU0_SB_DQ<26>
  VSS122  = GND
  DQ27_B  = M_E_CPU0_SB_DQ<27>
  VSS123  = GND
  \dqs8_b_c||tdqs8_b_c\  = M_E_CPU0_SB_DQS_DN<8>
  \dqs8_b_t||tdqs8_b_t\  = M_E_CPU0_SB_DQS_DP<8>
  VSS124  = GND
  DQ30_B  = M_E_CPU0_SB_DQ<30>
  VSS125  = GND
  DQ31_B  = M_E_CPU0_SB_DQ<31>
  VSS126  = GND
  G1  = GND
  G2  = GND
  G3  = GND

(kicad_pcb
	(version 20260206)
	(generator "pcbnew")
	(generator_version "10.0")
	(general
		(thickness 1.6)
		(legacy_teardrops no)
	)
	(paper "A4")
	(title_block
		(title "03242023_DA0F0TMBIJ0_F0T_Motherboard_J_brd_V01_OCP.brd")
		(comment 1 "Grand Teton / footprint 1607 of 6105 (J10), pads 138-182 of 291")
	)
	(layers
		(0 "F.Cu" signal "TOP")
		(4 "In1.Cu" signal "GND")
		(6 "In2.Cu" signal "IN1")
		(8 "In3.Cu" signal "GND1")
		(10 "In4.Cu" signal "IN2")
		(12 "In5.Cu" signal "GND2")
		(14 "In6.Cu" signal "IN3")
		(16 "In7.Cu" signal "GND3")
		(18 "In8.Cu" signal "VCC")
		(20 "In9.Cu" signal "VCC1")
		(22 "In10.Cu" signal "GND4")
		(24 "In11.Cu" signal "IN4")
		(26 "In12.Cu" signal "GND5")
		(28 "In13.Cu" signal "IN5")
		(30 "In14.Cu" signal "GND6")
		(32 "In15.Cu" signal "IN6")
		(34 "In16.Cu" signal "GND7")
		(2 "B.Cu" signal "BOTTOM")
		(9 "F.Adhes" user "F.Adhesive")
		(11 "B.Adhes" user "B.Adhesive")
		(13 "F.Paste" user "Package Geometry/Pastemask Top")
		(15 "B.Paste" user "Package Geometry/Pastemask Bottom")
		(5 "F.SilkS" user "Ref Des/Silkscreen Top")
		(7 "B.SilkS" user "Ref Des/Silkscreen Bottom")
		(1 "F.Mask" user "Board Geometry/Soldermask Top")
		(3 "B.Mask" user "Board Geometry/Soldermask Bottom")
		(17 "Dwgs.User" user "User.Drawings")
		(19 "Cmts.User" user "User.Comments")
		(21 "Eco1.User" user "User.Eco1")
		(23 "Eco2.User" user "User.Eco2")
		(25 "Edge.Cuts" user "Board Geometry/Outline")
		(27 "Margin" user)
		(31 "F.CrtYd" user "Package Geometry/Place Bound Top")
		(29 "B.CrtYd" user "Package Geometry/Place Bound Bottom")
		(35 "F.Fab" user "Ref Des/Assembly Top")
		(33 "B.Fab" user "Ref Des/Assembly Bottom")
	)
	(footprint ""
		(layer "F.Cu")
		(at 408.803348 -258.091686)
		(property "Reference" "J10"
			(at -3.683 -81.702148 0)
			(unlocked yes)
			(layer "F.SilkS")
			(effects
				(font
					(size 0.7874 0.5842)
					(thickness 0.1524)
				)
				(justify left)
			)
		)
		(property "Value" ""
			(at 0 0 0)
			(layer "F.Fab")
			(effects
				(font
					(size 1.27 1.27)
				)
			)
		)
		(duplicate_pad_numbers_are_jumpers no)
		(pad "138" smd rect
			(at -2.050034 58.224928 270)
			(size 0.519938 1.4986)
			(layers "F.Cu" "F.Mask" "F.Paste")
			(net "M_E_CPU0_SB_DQS_DN<3>")
		)
		(pad "139" smd rect
			(at -2.050034 59.075066 270)
			(size 0.519938 1.4986)
			(layers "F.Cu" "F.Mask" "F.Paste")
			(net "GND")
		)
		(pad "140" smd rect
			(at -2.050034 59.92495 270)
			(size 0.519938 1.4986)
			(layers "F.Cu" "F.Mask" "F.Paste")
			(net "M_E_CPU0_SB_DQ<28>")
		)
		(pad "141" smd rect
			(at -2.050034 60.775088 270)
			(size 0.519938 1.4986)
			(layers "F.Cu" "F.Mask" "F.Paste")
			(net "GND")
		)
		(pad "142" smd rect
			(at -2.050034 61.624972 270)
			(size 0.519938 1.4986)
			(layers "F.Cu" "F.Mask" "F.Paste")
			(net "M_E_CPU0_SB_DQ<29>")
		)
		(pad "143" smd rect
			(at -2.050034 62.47511 270)
			(size 0.519938 1.4986)
			(layers "F.Cu" "F.Mask" "F.Paste")
			(net "GND")
		)
		(pad "144" smd rect
			(at -2.050034 63.324994 270)
			(size 0.519938 1.4986)
			(layers "F.Cu" "F.Mask" "F.Paste")
			(net "TP_CHE_CPU0_DIMM2_FRU_1")
		)
		(pad "145" smd rect
			(at 2.050034 -63.324994 270)
			(size 0.519938 1.4986)
			(layers "F.Cu" "F.Mask" "F.Paste")
			(net "P12V_S3_AUX_CPU0_NVDIMM")
		)
		(pad "146" smd rect
			(at 2.050034 -62.47511 270)
			(size 0.519938 1.4986)
			(layers "F.Cu" "F.Mask" "F.Paste")
			(net "P12V_S3_AUX_CPU0_NVDIMM")
		)
		(pad "147" smd rect
			(at 2.050034 -61.624972 270)
			(size 0.519938 1.4986)
			(layers "F.Cu" "F.Mask" "F.Paste")
			(net "PWRGD_CHE_CPU0_DIMM2")
		)
		(pad "148" smd rect
			(at 2.050034 -60.775088 270)
			(size 0.519938 1.4986)
			(layers "F.Cu" "F.Mask" "F.Paste")
			(net "PD_CHE_CPU0_DIMM2_SAA")
		)
		(pad "149" smd rect
			(at 2.050034 -59.92495 270)
			(size 0.519938 1.4986)
			(layers "F.Cu" "F.Mask" "F.Paste")
			(net "TP_CHE_CPU0_DIMM2_FRU_2")
		)
		(pad "150" smd rect
			(at 2.050034 -59.075066 270)
			(size 0.519938 1.4986)
			(layers "F.Cu" "F.Mask" "F.Paste")
			(net "TP_CHE_CPU0_DIMM2_FRU_3")
		)
		(pad "151" smd rect
			(at 2.050034 -58.224928 270)
			(size 0.519938 1.4986)
			(layers "F.Cu" "F.Mask" "F.Paste")
			(net "GND")
		)
		(pad "152" smd rect
			(at 2.050034 -57.375044 270)
			(size 0.519938 1.4986)
			(layers "F.Cu" "F.Mask" "F.Paste")
			(net "M_E_CPU0_SA_DQ<2>")
		)
		(pad "153" smd rect
			(at 2.050034 -56.524906 270)
			(size 0.519938 1.4986)
			(layers "F.Cu" "F.Mask" "F.Paste")
			(net "GND")
		)
		(pad "154" smd rect
			(at 2.050034 -55.675022 270)
			(size 0.519938 1.4986)
			(layers "F.Cu" "F.Mask" "F.Paste")
			(net "M_E_CPU0_SA_DQ<3>")
		)
		(pad "155" smd rect
			(at 2.050034 -54.824884 270)
			(size 0.519938 1.4986)
			(layers "F.Cu" "F.Mask" "F.Paste")
			(net "GND")
		)
		(pad "156" smd rect
			(at 2.050034 -53.975 270)
			(size 0.519938 1.4986)
			(layers "F.Cu" "F.Mask" "F.Paste")
			(net "M_E_CPU0_SA_DQS_DN<5>")
		)
		(pad "157" smd rect
			(at 2.050034 -53.125116 270)
			(size 0.519938 1.4986)
			(layers "F.Cu" "F.Mask" "F.Paste")
			(net "M_E_CPU0_SA_DQS_DP<5>")
		)
		(pad "158" smd rect
			(at 2.050034 -52.274978 270)
			(size 0.519938 1.4986)
			(layers "F.Cu" "F.Mask" "F.Paste")
			(net "GND")
		)
		(pad "159" smd rect
			(at 2.050034 -51.425094 270)
			(size 0.519938 1.4986)
			(layers "F.Cu" "F.Mask" "F.Paste")
			(net "M_E_CPU0_SA_DQ<6>")
		)
		(pad "160" smd rect
			(at 2.050034 -50.574956 270)
			(size 0.519938 1.4986)
			(layers "F.Cu" "F.Mask" "F.Paste")
			(net "GND")
		)
		(pad "161" smd rect
			(at 2.050034 -49.725072 270)
			(size 0.519938 1.4986)
			(layers "F.Cu" "F.Mask" "F.Paste")
			(net "M_E_CPU0_SA_DQ<7>")
		)
		(pad "162" smd rect
			(at 2.050034 -48.874934 270)
			(size 0.519938 1.4986)
			(layers "F.Cu" "F.Mask" "F.Paste")
			(net "GND")
		)
		(pad "163" smd rect
			(at 2.050034 -48.02505 270)
			(size 0.519938 1.4986)
			(layers "F.Cu" "F.Mask" "F.Paste")
			(net "M_E_CPU0_SA_DQ<10>")
		)
		(pad "164" smd rect
			(at 2.050034 -47.174912 270)
			(size 0.519938 1.4986)
			(layers "F.Cu" "F.Mask" "F.Paste")
			(net "GND")
		)
		(pad "165" smd rect
			(at 2.050034 -46.325028 270)
			(size 0.519938 1.4986)
			(layers "F.Cu" "F.Mask" "F.Paste")
			(net "M_E_CPU0_SA_DQ<11>")
		)
		(pad "166" smd rect
			(at 2.050034 -45.47489 270)
			(size 0.519938 1.4986)
			(layers "F.Cu" "F.Mask" "F.Paste")
			(net "GND")
		)
		(pad "167" smd rect
			(at 2.050034 -44.625006 270)
			(size 0.519938 1.4986)
			(layers "F.Cu" "F.Mask" "F.Paste")
			(net "M_E_CPU0_SA_DQS_DN<6>")
		)
		(pad "168" smd rect
			(at 2.050034 -43.775122 270)
			(size 0.519938 1.4986)
			(layers "F.Cu" "F.Mask" "F.Paste")
			(net "M_E_CPU0_SA_DQS_DP<6>")
		)
		(pad "169" smd rect
			(at 2.050034 -42.924984 270)
			(size 0.519938 1.4986)
			(layers "F.Cu" "F.Mask" "F.Paste")
			(net "GND")
		)
		(pad "170" smd rect
			(at 2.050034 -42.0751 270)
			(size 0.519938 1.4986)
			(layers "F.Cu" "F.Mask" "F.Paste")
			(net "M_E_CPU0_SA_DQ<14>")
		)
		(pad "171" smd rect
			(at 2.050034 -41.224962 270)
			(size 0.519938 1.4986)
			(layers "F.Cu" "F.Mask" "F.Paste")
			(net "GND")
		)
		(pad "172" smd rect
			(at 2.050034 -40.375078 270)
			(size 0.519938 1.4986)
			(layers "F.Cu" "F.Mask" "F.Paste")
			(net "M_E_CPU0_SA_DQ<15>")
		)
		(pad "173" smd rect
			(at 2.050034 -39.52494 270)
			(size 0.519938 1.4986)
			(layers "F.Cu" "F.Mask" "F.Paste")
			(net "GND")
		)
		(pad "174" smd rect
			(at 2.050034 -38.675056 270)
			(size 0.519938 1.4986)
			(layers "F.Cu" "F.Mask" "F.Paste")
			(net "M_E_CPU0_SA_DQ<18>")
		)
		(pad "175" smd rect
			(at 2.050034 -37.824918 270)
			(size 0.519938 1.4986)
			(layers "F.Cu" "F.Mask" "F.Paste")
			(net "GND")
		)
		(pad "176" smd rect
			(at 2.050034 -36.975034 270)
			(size 0.519938 1.4986)
			(layers "F.Cu" "F.Mask" "F.Paste")
			(net "M_E_CPU0_SA_DQ<19>")
		)
		(pad "177" smd rect
			(at 2.050034 -36.124896 270)
			(size 0.519938 1.4986)
			(layers "F.Cu" "F.Mask" "F.Paste")
			(net "GND")
		)
		(pad "178" smd rect
			(at 2.050034 -35.275012 270)
			(size 0.519938 1.4986)
			(layers "F.Cu" "F.Mask" "F.Paste")
			(net "M_E_CPU0_SA_DQS_DN<7>")
		)
		(pad "179" smd rect
			(at 2.050034 -34.425128 270)
			(size 0.519938 1.4986)
			(layers "F.Cu" "F.Mask" "F.Paste")
			(net "M_E_CPU0_SA_DQS_DP<7>")
		)
		(pad "180" smd rect
			(at 2.050034 -33.57499 270)
			(size 0.519938 1.4986)
			(layers "F.Cu" "F.Mask" "F.Paste")
			(net "GND")
		)
		(pad "181" smd rect
			(at 2.050034 -32.725106 270)
			(size 0.519938 1.4986)
			(layers "F.Cu" "F.Mask" "F.Paste")
			(net "M_E_CPU0_SA_DQ<22>")
		)
		(pad "182" smd rect
			(at 2.050034 -31.874968 270)
			(size 0.519938 1.4986)
			(layers "F.Cu" "F.Mask" "F.Paste")
			(net "GND")
		)
	)
)
